# T6G (Grand Teton) — schematic netlist excerpt (pin names and nets, part order shuffled) for the footprints in the layout excerpt that follows; sources: Cadence DE-HDL packaged netlist, KiCad conversion of 04192023_DAF0TMB3IC0_F0TG_MB_C_brd_V02_OCP.brd

PC506  Q_CAP  2.2UF 10V 10% X6S  pkg C0402  page 225 : A = PVDD11_S3_P1_VCC2 ; B = GND
R4059  Q_RES  0 5% EMPTY  pkg 0402LF  page 140 : A = P12V_OCP_V3_2_EN_R ; B = P12V_OCP_EN_2_R

(kicad_pcb
	(version 20260206)
	(generator "pcbnew")
	(generator_version "10.0")
	(general
		(thickness 1.6)
		(legacy_teardrops no)
	)
	(paper "A4")
	(title_block
		(title "04192023_DAF0TMB3IC0_F0TG_MB_C_brd_V02_OCP.brd")
		(comment 1 "Grand Teton / footprints 2716-2717 of 8354")
	)
	(layers
		(0 "F.Cu" signal "TOP")
		(4 "In1.Cu" signal "GND")
		(6 "In2.Cu" signal "IN1")
		(8 "In3.Cu" signal "GND1")
		(10 "In4.Cu" signal "IN2")
		(12 "In5.Cu" signal "GND2")
		(14 "In6.Cu" signal "IN3")
		(16 "In7.Cu" signal "GND3")
		(18 "In8.Cu" signal "VCC")
		(20 "In9.Cu" signal "VCC1")
		(22 "In10.Cu" signal "GND4")
		(24 "In11.Cu" signal "IN4")
		(26 "In12.Cu" signal "GND5")
		(28 "In13.Cu" signal "IN5")
		(30 "In14.Cu" signal "GND6")
		(32 "In15.Cu" signal "IN6")
		(34 "In16.Cu" signal "GND7")
		(2 "B.Cu" signal "BOTTOM")
		(9 "F.Adhes" user "F.Adhesive")
		(11 "B.Adhes" user "B.Adhesive")
		(13 "F.Paste" user "Package Geometry/Pastemask Top")
		(15 "B.Paste" user "Package Geometry/Pastemask Bottom")
		(5 "F.SilkS" user "Ref Des/Silkscreen Top")
		(7 "B.SilkS" user "Ref Des/Silkscreen Bottom")
		(1 "F.Mask" user "Board Geometry/Soldermask Top")
		(3 "B.Mask" user "Board Geometry/Soldermask Bottom")
		(17 "Dwgs.User" user "User.Drawings")
		(19 "Cmts.User" user "User.Comments")
		(21 "Eco1.User" user "User.Eco1")
		(23 "Eco2.User" user "User.Eco2")
		(25 "Edge.Cuts" user "Board Geometry/Outline")
		(27 "Margin" user)
		(31 "F.CrtYd" user "Package Geometry/Place Bound Top")
		(29 "B.CrtYd" user "Package Geometry/Place Bound Bottom")
		(35 "F.Fab" user "Ref Des/Assembly Top")
		(33 "B.Fab" user "Ref Des/Assembly Bottom")
	)
	(footprint ""
		(layer "F.Cu")
		(at 65.572894 -35.784028)
		(property "Reference" "R4059"
			(at 0 0 0)
			(layer "F.SilkS")
			(hide yes)
			(effects
				(font
					(size 1.27 1.27)
				)
			)
		)
		(property "Value" ""
			(at 0 0 0)
			(layer "F.Fab")
			(effects
				(font
					(size 1.27 1.27)
				)
			)
		)
		(duplicate_pad_numbers_are_jumpers no)
		(fp_line
			(start -0.7874 -0.4064)
			(end 0.7874 -0.4064)
			(stroke
				(width 0.1524)
				(type default)
			)
			(layer "F.SilkS")
		)
		(fp_line
			(start -0.7874 0.4064)
			(end -0.7874 -0.4064)
			(stroke
				(width 0.1524)
				(type default)
			)
			(layer "F.SilkS")
		)
		(fp_line
			(start 0.7874 -0.4064)
			(end 0.7874 0.4064)
			(stroke
				(width 0.1524)
				(type default)
			)
			(layer "F.SilkS")
		)
		(fp_line
			(start 0.7874 0.4064)
			(end -0.7874 0.4064)
			(stroke
				(width 0.1524)
				(type default)
			)
			(layer "F.SilkS")
		)
		(fp_line
			(start -0.67945 -0.305054)
			(end -0.12065 -0.305054)
			(stroke
				(width 0.1)
				(type default)
			)
			(layer "F.Fab")
		)
		(fp_line
			(start -0.67945 0.3048)
			(end -0.67945 -0.305054)
			(stroke
				(width 0.1)
				(type default)
			)
			(layer "F.Fab")
		)
		(fp_line
			(start -0.12065 -0.305054)
			(end -0.12065 -0.2794)
			(stroke
				(width 0.1)
				(type default)
			)
			(layer "F.Fab")
		)
		(fp_line
			(start -0.12065 -0.2794)
			(end 0.12065 -0.2794)
			(stroke
				(width 0.1)
				(type default)
			)
			(layer "F.Fab")
		)
		(fp_line
			(start -0.12065 0.2794)
			(end -0.12065 0.3048)
			(stroke
				(width 0.1)
				(type default)
			)
			(layer "F.Fab")
		)
		(fp_line
			(start -0.12065 0.3048)
			(end -0.67945 0.3048)
			(stroke
				(width 0.1)
				(type default)
			)
			(layer "F.Fab")
		)
		(fp_line
			(start 0.120396 0.2794)
			(end -0.12065 0.2794)
			(stroke
				(width 0.1)
				(type default)
			)
			(layer "F.Fab")
		)
		(fp_line
			(start 0.120396 0.3048)
			(end 0.120396 0.2794)
			(stroke
				(width 0.1)
				(type default)
			)
			(layer "F.Fab")
		)
		(fp_line
			(start 0.12065 -0.3048)
			(end 0.67945 -0.3048)
			(stroke
				(width 0.1)
				(type default)
			)
			(layer "F.Fab")
		)
		(fp_line
			(start 0.12065 -0.2794)
			(end 0.12065 -0.3048)
			(stroke
				(width 0.1)
				(type default)
			)
			(layer "F.Fab")
		)
		(fp_line
			(start 0.67945 -0.3048)
			(end 0.67945 0.3048)
			(stroke
				(width 0.1)
				(type default)
			)
			(layer "F.Fab")
		)
		(fp_line
			(start 0.67945 0.3048)
			(end 0.120396 0.3048)
			(stroke
				(width 0.1)
				(type default)
			)
			(layer "F.Fab")
		)
		(pad "1" smd circle
			(at -0.40005 0)
			(size 0 0)
			(layers "F.Cu" "F.Mask" "F.Paste")
			(net "P12V_OCP_V3_2_EN_R")
		)
		(pad "2" smd circle
			(at 0.40005 0)
			(size 0 0)
			(layers "F.Cu" "F.Mask" "F.Paste")
			(net "P12V_OCP_EN_2_R")
		)
	)
	(footprint ""
		(layer "F.Cu")
		(at 187.563506 -353.986084 90)
		(property "Reference" "PC506"
			(at 0 0 90)
			(layer "F.SilkS")
			(hide yes)
			(effects
				(font
					(size 1.27 1.27)
				)
			)
		)
		(property "Value" ""
			(at 0 0 90)
			(layer "F.Fab")
			(effects
				(font
					(size 1.27 1.27)
				)
			)
		)
		(duplicate_pad_numbers_are_jumpers no)
		(fp_line
			(start 0.7874 -0.4064)
			(end 0.7874 0.4064)
			(stroke
				(width 0.1524)
				(type default)
			)
			(layer "F.SilkS")
		)
		(fp_line
			(start -0.7874 -0.4064)
			(end 0.7874 -0.4064)
			(stroke
				(width 0.1524)
				(type default)
			)
			(layer "F.SilkS")
		)
		(fp_line
			(start 0.7874 0.4064)
			(end 0.445516 0.4064)
			(stroke
				(width 0.1524)
				(type default)
			)
			(layer "F.SilkS")
		)
		(fp_line
			(start -0.291084 0.4064)
			(end -0.7874 0.4064)
			(stroke
				(width 0.1524)
				(type default)
			)
			(layer "F.SilkS")
		)
		(fp_line
			(start -0.7874 0.4064)
			(end -0.7874 -0.4064)
			(stroke
				(width 0.1524)
				(type default)
			)
			(layer "F.SilkS")
		)
		(fp_line
			(start -0.12065 -0.305054)
			(end -0.12065 -0.2794)
			(stroke
				(width 0.1)
				(type default)
			)
			(layer "F.Fab")
		)
		(fp_line
			(start -0.67945 -0.305054)
			(end -0.12065 -0.305054)
			(stroke
				(width 0.1)
				(type default)
			)
			(layer "F.Fab")
		)
		(fp_line
			(start 0.67945 -0.3048)
			(end 0.67945 0.3048)
			(stroke
				(width 0.1)
				(type default)
			)
			(layer "F.Fab")
		)
		(fp_line
			(start 0.12065 -0.3048)
			(end 0.67945 -0.3048)
			(stroke
				(width 0.1)
				(type default)
			)
			(layer "F.Fab")
		)
		(fp_line
			(start 0.12065 -0.2794)
			(end 0.12065 -0.3048)
			(stroke
				(width 0.1)
				(type default)
			)
			(layer "F.Fab")
		)
		(fp_line
			(start -0.12065 -0.2794)
			(end 0.12065 -0.2794)
			(stroke
				(width 0.1)
				(type default)
			)
			(layer "F.Fab")
		)
		(fp_line
			(start 0.120396 0.2794)
			(end -0.12065 0.2794)
			(stroke
				(width 0.1)
				(type default)
			)
			(layer "F.Fab")
		)
		(fp_line
			(start -0.12065 0.2794)
			(end -0.12065 0.3048)
			(stroke
				(width 0.1)
				(type default)
			)
			(layer "F.Fab")
		)
		(fp_line
			(start 0.67945 0.3048)
			(end 0.120396 0.3048)
			(stroke
				(width 0.1)
				(type default)
			)
			(layer "F.Fab")
		)
		(fp_line
			(start 0.120396 0.3048)
			(end 0.120396 0.2794)
			(stroke
				(width 0.1)
				(type default)
			)
			(layer "F.Fab")
		)
		(fp_line
			(start -0.12065 0.3048)
			(end -0.67945 0.3048)
			(stroke
				(width 0.1)
				(type default)
			)
			(layer "F.Fab")
		)
		(fp_line
			(start -0.67945 0.3048)
			(end -0.67945 -0.305054)
			(stroke
				(width 0.1)
				(type default)
			)
			(layer "F.Fab")
		)
		(pad "1" smd circle
			(at -0.40005 0 90)
			(size 0 0)
			(layers "F.Cu" "F.Mask" "F.Paste")
			(net "PVDD11_S3_P1_VCC2")
		)
		(pad "2" smd circle
			(at 0.40005 0 90)
			(size 0 0)
			(layers "F.Cu" "F.Mask" "F.Paste")
			(net "GND")
		)
	)
)
